(kicad_pcb
	(version 20260206)
	(generator "pcbnew")
	(generator_version "10.0")
	(general
		(thickness 1.6)
		(legacy_teardrops no)
	)
	(paper "A4")
	(title_block
		(title "01162023_DA0F0TEBIF0_F0T_Expander_BD_F_brd_V02_OCP.brd")
		(comment 1 "Grand Teton / footprints 5226-5233 of 9728")
	)
	(layers
		(0 "F.Cu" signal "TOP")
		(4 "In1.Cu" signal "GND")
		(6 "In2.Cu" signal "VCC")
		(8 "In3.Cu" signal "VCC1")
		(10 "In4.Cu" signal "GND1")
		(12 "In5.Cu" signal "IN1")
		(14 "In6.Cu" signal "GND2")
		(16 "In7.Cu" signal "IN2")
		(18 "In8.Cu" signal "GND3")
		(20 "In9.Cu" signal "IN3")
		(22 "In10.Cu" signal "GND4")
		(24 "In11.Cu" signal "IN4")
		(26 "In12.Cu" signal "GND5")
		(28 "In13.Cu" signal "IN5")
		(30 "In14.Cu" signal "GND6")
		(32 "In15.Cu" signal "IN6")
		(34 "In16.Cu" signal "GND7")
		(2 "B.Cu" signal "BOTTOM")
		(9 "F.Adhes" user "F.Adhesive")
		(11 "B.Adhes" user "B.Adhesive")
		(13 "F.Paste" user "Package Geometry/Pastemask Top")
		(15 "B.Paste" user "Package Geometry/Pastemask Bottom")
		(5 "F.SilkS" user "Ref Des/Silkscreen Top")
		(7 "B.SilkS" user "Ref Des/Silkscreen Bottom")
		(1 "F.Mask" user "Board Geometry/Soldermask Top")
		(3 "B.Mask" user "Board Geometry/Soldermask Bottom")
		(17 "Dwgs.User" user "User.Drawings")
		(19 "Cmts.User" user "User.Comments")
		(21 "Eco1.User" user "User.Eco1")
		(23 "Eco2.User" user "User.Eco2")
		(25 "Edge.Cuts" user "Board Geometry/Outline")
		(27 "Margin" user)
		(31 "F.CrtYd" user "Package Geometry/Place Bound Top")
		(29 "B.CrtYd" user "Package Geometry/Place Bound Bottom")
		(35 "F.Fab" user "Ref Des/Assembly Top")
		(33 "B.Fab" user "Ref Des/Assembly Bottom")
	)
	(footprint ""
		(layer "F.Cu")
		(at 334.772 -241.808 90)
		(property "Reference" "U145"
			(at 0 -1.67513 90)
			(unlocked yes)
			(layer "F.SilkS")
			(effects
				(font
					(size 0.7874 0.5842)
					(thickness 0.1524)
				)
			)
		)
		(property "Value" ""
			(at 0 0 90)
			(layer "F.Fab")
			(effects
				(font
					(size 1.27 1.27)
				)
			)
		)
		(duplicate_pad_numbers_are_jumpers no)
		(fp_line
			(start 1.7272 -1.1176)
			(end 0.254 -1.1176)
			(stroke
				(width 0.1524)
				(type default)
			)
			(layer "F.SilkS")
		)
		(fp_line
			(start 1.7272 -1.1176)
			(end 1.7272 1.1176)
			(stroke
				(width 0.1524)
				(type default)
			)
			(layer "F.SilkS")
		)
		(fp_line
			(start 0.254 -1.1176)
			(end 0 -0.7366)
			(stroke
				(width 0.1524)
				(type default)
			)
			(layer "F.SilkS")
		)
		(fp_line
			(start -0.254 -1.1176)
			(end -1.7272 -1.1176)
			(stroke
				(width 0.1524)
				(type default)
			)
			(layer "F.SilkS")
		)
		(fp_line
			(start 0 -0.7366)
			(end -0.254 -1.1176)
			(stroke
				(width 0.1524)
				(type default)
			)
			(layer "F.SilkS")
		)
		(fp_line
			(start 1.7272 1.1176)
			(end -1.7272 1.1176)
			(stroke
				(width 0.1524)
				(type default)
			)
			(layer "F.SilkS")
		)
		(fp_line
			(start -1.7272 1.1176)
			(end -1.7272 -1.1176)
			(stroke
				(width 0.1524)
				(type default)
			)
			(layer "F.SilkS")
		)
		(fp_poly
			(pts
				(xy -1.9558 -0.649986) (xy -2.7178 -0.268986) (xy -2.7178 -1.030986)
			)
			(stroke
				(width 0)
				(type default)
			)
			(fill yes)
			(layer "F.SilkS")
		)
		(fp_line
			(start 1.5748 -1.1176)
			(end -1.5748 -1.1176)
			(stroke
				(width 0.1)
				(type default)
			)
			(layer "F.Fab")
		)
		(fp_line
			(start -1.5748 -1.1176)
			(end -1.5748 1.1176)
			(stroke
				(width 0.1)
				(type default)
			)
			(layer "F.Fab")
		)
		(fp_line
			(start 1.5748 1.1176)
			(end 1.5748 -1.1176)
			(stroke
				(width 0.1)
				(type default)
			)
			(layer "F.Fab")
		)
		(fp_line
			(start -1.5748 1.1176)
			(end 1.5748 1.1176)
			(stroke
				(width 0.1)
				(type default)
			)
			(layer "F.Fab")
		)
		(fp_poly
			(pts
				(xy -1.9558 -0.649986) (xy -2.7178 -0.268986) (xy -2.7178 -1.030986)
			)
			(stroke
				(width 0)
				(type default)
			)
			(fill yes)
			(layer "F.Fab")
		)
		(pad "1" smd rect
			(at -0.999998 -0.649986)
			(size 0.3556 1.1176)
			(layers "F.Cu" "F.Mask" "F.Paste")
			(net "MB_SWB_PWRGD_R")
		)
		(pad "2" smd rect
			(at -0.999998 0)
			(size 0.3556 1.1176)
			(layers "F.Cu" "F.Mask" "F.Paste")
			(net "GND")
		)
		(pad "3" smd rect
			(at -0.999998 0.649986)
			(size 0.3556 1.1176)
			(layers "F.Cu" "F.Mask" "F.Paste")
			(net "Net_585")
		)
		(pad "4" smd rect
			(at 0.999998 0.649986)
			(size 0.3556 1.1176)
			(layers "F.Cu" "F.Mask" "F.Paste")
			(net "Net_586")
		)
		(pad "5" smd rect
			(at 0.999998 0)
			(size 0.3556 1.1176)
			(layers "F.Cu" "F.Mask" "F.Paste")
			(net "P3V3_AUX")
		)
		(pad "6" smd rect
			(at 0.999998 -0.649986)
			(size 0.3556 1.1176)
			(layers "F.Cu" "F.Mask" "F.Paste")
			(net "MB_SWB_PWRGD_BUF")
		)
	)
	(footprint ""
		(layer "F.Cu")
		(at 13.476224 -306.924456 90)
		(property "Reference" "PR168"
			(at 0 0 90)
			(layer "F.SilkS")
			(hide yes)
			(effects
				(font
					(size 1.27 1.27)
				)
			)
		)
		(property "Value" ""
			(at 0 0 90)
			(layer "F.Fab")
			(effects
				(font
					(size 1.27 1.27)
				)
			)
		)
		(duplicate_pad_numbers_are_jumpers no)
		(fp_line
			(start 0.7874 -0.4064)
			(end 0.7874 0.4064)
			(stroke
				(width 0.1524)
				(type default)
			)
			(layer "F.SilkS")
		)
		(fp_line
			(start -0.7874 -0.4064)
			(end 0.7874 -0.4064)
			(stroke
				(width 0.1524)
				(type default)
			)
			(layer "F.SilkS")
		)
		(fp_line
			(start 0.7874 0.4064)
			(end -0.7874 0.4064)
			(stroke
				(width 0.1524)
				(type default)
			)
			(layer "F.SilkS")
		)
		(fp_line
			(start -0.7874 0.4064)
			(end -0.7874 -0.4064)
			(stroke
				(width 0.1524)
				(type default)
			)
			(layer "F.SilkS")
		)
		(fp_line
			(start -0.12065 -0.305054)
			(end -0.12065 -0.2794)
			(stroke
				(width 0.1)
				(type default)
			)
			(layer "F.Fab")
		)
		(fp_line
			(start -0.67945 -0.305054)
			(end -0.12065 -0.305054)
			(stroke
				(width 0.1)
				(type default)
			)
			(layer "F.Fab")
		)
		(fp_line
			(start 0.67945 -0.3048)
			(end 0.67945 0.3048)
			(stroke
				(width 0.1)
				(type default)
			)
			(layer "F.Fab")
		)
		(fp_line
			(start 0.12065 -0.3048)
			(end 0.67945 -0.3048)
			(stroke
				(width 0.1)
				(type default)
			)
			(layer "F.Fab")
		)
		(fp_line
			(start 0.12065 -0.2794)
			(end 0.12065 -0.3048)
			(stroke
				(width 0.1)
				(type default)
			)
			(layer "F.Fab")
		)
		(fp_line
			(start -0.12065 -0.2794)
			(end 0.12065 -0.2794)
			(stroke
				(width 0.1)
				(type default)
			)
			(layer "F.Fab")
		)
		(fp_line
			(start 0.120396 0.2794)
			(end -0.12065 0.2794)
			(stroke
				(width 0.1)
				(type default)
			)
			(layer "F.Fab")
		)
		(fp_line
			(start -0.12065 0.2794)
			(end -0.12065 0.3048)
			(stroke
				(width 0.1)
				(type default)
			)
			(layer "F.Fab")
		)
		(fp_line
			(start 0.67945 0.3048)
			(end 0.120396 0.3048)
			(stroke
				(width 0.1)
				(type default)
			)
			(layer "F.Fab")
		)
		(fp_line
			(start 0.120396 0.3048)
			(end 0.120396 0.2794)
			(stroke
				(width 0.1)
				(type default)
			)
			(layer "F.Fab")
		)
		(fp_line
			(start -0.12065 0.3048)
			(end -0.67945 0.3048)
			(stroke
				(width 0.1)
				(type default)
			)
			(layer "F.Fab")
		)
		(fp_line
			(start -0.67945 0.3048)
			(end -0.67945 -0.305054)
			(stroke
				(width 0.1)
				(type default)
			)
			(layer "F.Fab")
		)
		(pad "1" smd circle
			(at -0.40005 0 90)
			(size 0 0)
			(layers "F.Cu" "F.Mask" "F.Paste")
			(net "SH_P1V25_PEX0_FB_N")
		)
		(pad "2" smd circle
			(at 0.40005 0 90)
			(size 0 0)
			(layers "F.Cu" "F.Mask" "F.Paste")
			(net "P1V25_PEX0_FB")
		)
	)
	(footprint ""
		(layer "F.Cu")
		(at 65.370202 -350.098614 90)
		(property "Reference" "C132"
			(at 0 0 90)
			(layer "F.SilkS")
			(hide yes)
			(effects
				(font
					(size 1.27 1.27)
				)
			)
		)
		(property "Value" ""
			(at 0 0 90)
			(layer "F.Fab")
			(effects
				(font
					(size 1.27 1.27)
				)
			)
		)
		(duplicate_pad_numbers_are_jumpers no)
		(fp_line
			(start 0.299974 -0.150114)
			(end 0.299974 0.150114)
			(stroke
				(width 0.1)
				(type default)
			)
			(layer "F.Fab")
		)
		(fp_line
			(start -0.299974 -0.150114)
			(end 0.299974 -0.150114)
			(stroke
				(width 0.1)
				(type default)
			)
			(layer "F.Fab")
		)
		(fp_line
			(start 0.299974 0.150114)
			(end -0.299974 0.150114)
			(stroke
				(width 0.1)
				(type default)
			)
			(layer "F.Fab")
		)
		(fp_line
			(start -0.299974 0.150114)
			(end -0.299974 -0.150114)
			(stroke
				(width 0.1)
				(type default)
			)
			(layer "F.Fab")
		)
		(pad "1" smd rect
			(at -0.2667 0 90)
			(size 0.3048 0.381)
			(layers "F.Cu" "F.Mask" "F.Paste")
			(net "P5E_PEX0_STN6_TX_DN<110>")
		)
		(pad "2" smd rect
			(at 0.2667 0 90)
			(size 0.3048 0.381)
			(layers "F.Cu" "F.Mask" "F.Paste")
			(net "P5E_PEX0_STN6_TX_C_DN<110>")
		)
	)
	(footprint ""
		(layer "F.Cu")
		(at 403.16658 -350.098614 90)
		(property "Reference" "C747"
			(at 0 0 90)
			(layer "F.SilkS")
			(hide yes)
			(effects
				(font
					(size 1.27 1.27)
				)
			)
		)
		(property "Value" ""
			(at 0 0 90)
			(layer "F.Fab")
			(effects
				(font
					(size 1.27 1.27)
				)
			)
		)
		(duplicate_pad_numbers_are_jumpers no)
		(fp_line
			(start 0.299974 -0.150114)
			(end 0.299974 0.150114)
			(stroke
				(width 0.1)
				(type default)
			)
			(layer "F.Fab")
		)
		(fp_line
			(start -0.299974 -0.150114)
			(end 0.299974 -0.150114)
			(stroke
				(width 0.1)
				(type default)
			)
			(layer "F.Fab")
		)
		(fp_line
			(start 0.299974 0.150114)
			(end -0.299974 0.150114)
			(stroke
				(width 0.1)
				(type default)
			)
			(layer "F.Fab")
		)
		(fp_line
			(start -0.299974 0.150114)
			(end -0.299974 -0.150114)
			(stroke
				(width 0.1)
				(type default)
			)
			(layer "F.Fab")
		)
		(pad "1" smd rect
			(at -0.2667 0 90)
			(size 0.3048 0.381)
			(layers "F.Cu" "F.Mask" "F.Paste")
			(net "P5E_PEX3_STN5_TX_DN<87>")
		)
		(pad "2" smd rect
			(at 0.2667 0 90)
			(size 0.3048 0.381)
			(layers "F.Cu" "F.Mask" "F.Paste")
			(net "P5E_PEX3_STN5_TX_C_DN<87>")
		)
	)
	(footprint ""
		(layer "F.Cu")
		(at 43.792394 -31.825184 180)
		(property "Reference" "C76"
			(at 0 0 180)
			(layer "F.SilkS")
			(hide yes)
			(effects
				(font
					(size 1.27 1.27)
				)
			)
		)
		(property "Value" ""
			(at 0 0 180)
			(layer "F.Fab")
			(effects
				(font
					(size 1.27 1.27)
				)
			)
		)
		(duplicate_pad_numbers_are_jumpers no)
		(fp_line
			(start 0.299974 0.150114)
			(end -0.299974 0.150114)
			(stroke
				(width 0.1)
				(type default)
			)
			(layer "F.Fab")
		)
		(fp_line
			(start 0.299974 -0.150114)
			(end 0.299974 0.150114)
			(stroke
				(width 0.1)
				(type default)
			)
			(layer "F.Fab")
		)
		(fp_line
			(start -0.299974 0.150114)
			(end -0.299974 -0.150114)
			(stroke
				(width 0.1)
				(type default)
			)
			(layer "F.Fab")
		)
		(fp_line
			(start -0.299974 -0.150114)
			(end 0.299974 -0.150114)
			(stroke
				(width 0.1)
				(type default)
			)
			(layer "F.Fab")
		)
		(pad "1" smd rect
			(at -0.2667 0 180)
			(size 0.3048 0.381)
			(layers "F.Cu" "F.Mask" "F.Paste")
			(net "P5E_PEX0_STN2_TX_DN<42>")
		)
		(pad "2" smd rect
			(at 0.2667 0 180)
			(size 0.3048 0.381)
			(layers "F.Cu" "F.Mask" "F.Paste")
			(net "P5E_PEX0_STN2_TX_C_DN<42>")
		)
	)
	(footprint ""
		(layer "F.Cu")
		(at 245.732808 -310.571642 180)
		(property "Reference" "PR176"
			(at 0 0 180)
			(layer "F.SilkS")
			(hide yes)
			(effects
				(font
					(size 1.27 1.27)
				)
			)
		)
		(property "Value" ""
			(at 0 0 180)
			(layer "F.Fab")
			(effects
				(font
					(size 1.27 1.27)
				)
			)
		)
		(duplicate_pad_numbers_are_jumpers no)
		(fp_line
			(start 0.7874 0.4064)
			(end -0.7874 0.4064)
			(stroke
				(width 0.1524)
				(type default)
			)
			(layer "F.SilkS")
		)
		(fp_line
			(start 0.7874 -0.4064)
			(end 0.7874 0.4064)
			(stroke
				(width 0.1524)
				(type default)
			)
			(layer "F.SilkS")
		)
		(fp_line
			(start -0.7874 0.4064)
			(end -0.7874 -0.4064)
			(stroke
				(width 0.1524)
				(type default)
			)
			(layer "F.SilkS")
		)
		(fp_line
			(start -0.7874 -0.4064)
			(end 0.7874 -0.4064)
			(stroke
				(width 0.1524)
				(type default)
			)
			(layer "F.SilkS")
		)
		(fp_line
			(start 0.67945 0.3048)
			(end 0.120396 0.3048)
			(stroke
				(width 0.1)
				(type default)
			)
			(layer "F.Fab")
		)
		(fp_line
			(start 0.67945 -0.3048)
			(end 0.67945 0.3048)
			(stroke
				(width 0.1)
				(type default)
			)
			(layer "F.Fab")
		)
		(fp_line
			(start 0.12065 -0.2794)
			(end 0.12065 -0.3048)
			(stroke
				(width 0.1)
				(type default)
			)
			(layer "F.Fab")
		)
		(fp_line
			(start 0.12065 -0.3048)
			(end 0.67945 -0.3048)
			(stroke
				(width 0.1)
				(type default)
			)
			(layer "F.Fab")
		)
		(fp_line
			(start 0.120396 0.3048)
			(end 0.120396 0.2794)
			(stroke
				(width 0.1)
				(type default)
			)
			(layer "F.Fab")
		)
		(fp_line
			(start 0.120396 0.2794)
			(end -0.12065 0.2794)
			(stroke
				(width 0.1)
				(type default)
			)
			(layer "F.Fab")
		)
		(fp_line
			(start -0.12065 0.3048)
			(end -0.67945 0.3048)
			(stroke
				(width 0.1)
				(type default)
			)
			(layer "F.Fab")
		)
		(fp_line
			(start -0.12065 0.2794)
			(end -0.12065 0.3048)
			(stroke
				(width 0.1)
				(type default)
			)
			(layer "F.Fab")
		)
		(fp_line
			(start -0.12065 -0.2794)
			(end 0.12065 -0.2794)
			(stroke
				(width 0.1)
				(type default)
			)
			(layer "F.Fab")
		)
		(fp_line
			(start -0.12065 -0.305054)
			(end -0.12065 -0.2794)
			(stroke
				(width 0.1)
				(type default)
			)
			(layer "F.Fab")
		)
		(fp_line
			(start -0.67945 0.3048)
			(end -0.67945 -0.305054)
			(stroke
				(width 0.1)
				(type default)
			)
			(layer "F.Fab")
		)
		(fp_line
			(start -0.67945 -0.305054)
			(end -0.12065 -0.305054)
			(stroke
				(width 0.1)
				(type default)
			)
			(layer "F.Fab")
		)
		(pad "1" smd circle
			(at -0.40005 0 180)
			(size 0 0)
			(layers "F.Cu" "F.Mask" "F.Paste")
			(net "SH_P1V25_PEX2_FB_P")
		)
		(pad "2" smd circle
			(at 0.40005 0 180)
			(size 0 0)
			(layers "F.Cu" "F.Mask" "F.Paste")
			(net "P1V25_PEX2_FB")
		)
	)
	(footprint ""
		(layer "F.Cu")
		(at 198.76135 -136.20115 180)
		(property "Reference" "C228"
			(at 0 0 180)
			(layer "F.SilkS")
			(hide yes)
			(effects
				(font
					(size 1.27 1.27)
				)
			)
		)
		(property "Value" ""
			(at 0 0 180)
			(layer "F.Fab")
			(effects
				(font
					(size 1.27 1.27)
				)
			)
		)
		(duplicate_pad_numbers_are_jumpers no)
		(fp_line
			(start 0.299974 0.150114)
			(end -0.299974 0.150114)
			(stroke
				(width 0.1)
				(type default)
			)
			(layer "F.Fab")
		)
		(fp_line
			(start 0.299974 -0.150114)
			(end 0.299974 0.150114)
			(stroke
				(width 0.1)
				(type default)
			)
			(layer "F.Fab")
		)
		(fp_line
			(start -0.299974 0.150114)
			(end -0.299974 -0.150114)
			(stroke
				(width 0.1)
				(type default)
			)
			(layer "F.Fab")
		)
		(fp_line
			(start -0.299974 -0.150114)
			(end 0.299974 -0.150114)
			(stroke
				(width 0.1)
				(type default)
			)
			(layer "F.Fab")
		)
		(pad "1" smd rect
			(at -0.2667 0 180)
			(size 0.3048 0.381)
			(layers "F.Cu" "F.Mask" "F.Paste")
			(net "P5E_PEX1_STN0_TX_DP<7>")
		)
		(pad "2" smd rect
			(at 0.2667 0 180)
			(size 0.3048 0.381)
			(layers "F.Cu" "F.Mask" "F.Paste")
			(net "P5E_PEX1_STN0_TX_C_DP<7>")
		)
	)
	(footprint ""
		(layer "F.Cu")
		(at 212.738716 -22.867366 90)
		(property "Reference" "C3926"
			(at 0 0 90)
			(layer "F.SilkS")
			(hide yes)
			(effects
				(font
					(size 1.27 1.27)
				)
			)
		)
		(property "Value" ""
			(at 0 0 90)
			(layer "F.Fab")
			(effects
				(font
					(size 1.27 1.27)
				)
			)
		)
		(duplicate_pad_numbers_are_jumpers no)
		(fp_line
			(start 0.7874 -0.4064)
			(end 0.7874 0.4064)
			(stroke
				(width 0.1524)
				(type default)
			)
			(layer "F.SilkS")
		)
		(fp_line
			(start -0.7874 -0.4064)
			(end 0.7874 -0.4064)
			(stroke
				(width 0.1524)
				(type default)
			)
			(layer "F.SilkS")
		)
		(fp_line
			(start 0.7874 0.4064)
			(end -0.7874 0.4064)
			(stroke
				(width 0.1524)
				(type default)
			)
			(layer "F.SilkS")
		)
		(fp_line
			(start -0.7874 0.4064)
			(end -0.7874 -0.4064)
			(stroke
				(width 0.1524)
				(type default)
			)
			(layer "F.SilkS")
		)
		(fp_line
			(start -0.12065 -0.305054)
			(end -0.12065 -0.2794)
			(stroke
				(width 0.1)
				(type default)
			)
			(layer "F.Fab")
		)
		(fp_line
			(start -0.67945 -0.305054)
			(end -0.12065 -0.305054)
			(stroke
				(width 0.1)
				(type default)
			)
			(layer "F.Fab")
		)
		(fp_line
			(start 0.67945 -0.3048)
			(end 0.67945 0.3048)
			(stroke
				(width 0.1)
				(type default)
			)
			(layer "F.Fab")
		)
		(fp_line
			(start 0.12065 -0.3048)
			(end 0.67945 -0.3048)
			(stroke
				(width 0.1)
				(type default)
			)
			(layer "F.Fab")
		)
		(fp_line
			(start 0.12065 -0.2794)
			(end 0.12065 -0.3048)
			(stroke
				(width 0.1)
				(type default)
			)
			(layer "F.Fab")
		)
		(fp_line
			(start -0.12065 -0.2794)
			(end 0.12065 -0.2794)
			(stroke
				(width 0.1)
				(type default)
			)
			(layer "F.Fab")
		)
		(fp_line
			(start 0.120396 0.2794)
			(end -0.12065 0.2794)
			(stroke
				(width 0.1)
				(type default)
			)
			(layer "F.Fab")
		)
		(fp_line
			(start -0.12065 0.2794)
			(end -0.12065 0.3048)
			(stroke
				(width 0.1)
				(type default)
			)
			(layer "F.Fab")
		)
		(fp_line
			(start 0.67945 0.3048)
			(end 0.120396 0.3048)
			(stroke
				(width 0.1)
				(type default)
			)
			(layer "F.Fab")
		)
		(fp_line
			(start 0.120396 0.3048)
			(end 0.120396 0.2794)
			(stroke
				(width 0.1)
				(type default)
			)
			(layer "F.Fab")
		)
		(fp_line
			(start -0.12065 0.3048)
			(end -0.67945 0.3048)
			(stroke
				(width 0.1)
				(type default)
			)
			(layer "F.Fab")
		)
		(fp_line
			(start -0.67945 0.3048)
			(end -0.67945 -0.305054)
			(stroke
				(width 0.1)
				(type default)
			)
			(layer "F.Fab")
		)
		(pad "1" smd circle
			(at -0.40005 0 90)
			(size 0 0)
			(layers "F.Cu" "F.Mask" "F.Paste")
			(net "P12V_SSD7")
		)
		(pad "2" smd circle
			(at 0.40005 0 90)
			(size 0 0)
			(layers "F.Cu" "F.Mask" "F.Paste")
			(net "GND")
		)
	)
)
